# BASEBOARD_FAB2 (Tioga Pass) — schematic netlist excerpt (pin names and nets, part order shuffled) for the footprints in the layout excerpt that follows; sources: Cadence DE-HDL packaged netlist, KiCad conversion of Wiwynn_Tioga_Pass_MB.brd

EU7A3  IR354XX  IR35412 IC  pkg SM  page 236
  VOS  = PVNN_PCH_STBY
  LGND  = GND
  VCC  = VR_PVNN_PCH_PH1_VCIN
  VDRV  = P5V_STBY
  PGND(0)  = GND
  GL(0)  = TP_PVNN_PCH_GL_0
  PGND(1)  = GND
  SW  = VR_PVNN_PCH_PH1_PHASE_SW
  VIN(0)  = VR_FET_SW_P12V_STBY_PVDDQ_DEF
  VIN(1)  = VR_FET_SW_P12V_STBY_PVDDQ_DEF
  NC  = NC
  PHASE  = VR_PVNN_PCH_PH1_PHASE
  BOOST  = VR_PVNN_PCH_PH1_BOOT_R
  PWM  = VR_PVNN_PCH_PWM1
  EN  = P5V_STBY
  TOUT_FLT  = A_TSENSE_PVNN_PCH_TMON
  OCSET  = VR_PVNN_PCH_STBY_OCSET
  IOUT  = ISENSE_PVNN_PCH_PH1_IMON
  REFIN  = VR_PVNN_PCH_AIREF1
  PGND(2)  = GND
  GL(1)  = TP_PVNN_PCH_GL_1

(kicad_pcb
	(version 20260206)
	(generator "pcbnew")
	(generator_version "10.0")
	(general
		(thickness 1.6)
		(legacy_teardrops no)
	)
	(paper "A4")
	(title_block
		(title "Wiwynn_Tioga_Pass_MB.brd")
		(comment 1 "Tioga Pass / footprints 1618-1618 of 4770")
	)
	(layers
		(0 "F.Cu" signal "TOP")
		(4 "In1.Cu" signal "L2GND")
		(6 "In2.Cu" signal "L3")
		(8 "In3.Cu" signal "L4GND")
		(10 "In4.Cu" signal "L5")
		(12 "In5.Cu" signal "L6GND")
		(14 "In6.Cu" signal "L7VCC")
		(16 "In7.Cu" signal "L8VCC")
		(18 "In8.Cu" signal "L9GND")
		(20 "In9.Cu" signal "L10")
		(22 "In10.Cu" signal "L11GND")
		(24 "In11.Cu" signal "L12")
		(26 "In12.Cu" signal "L13GND")
		(2 "B.Cu" signal "BOTTOM")
		(9 "F.Adhes" user "F.Adhesive")
		(11 "B.Adhes" user "B.Adhesive")
		(13 "F.Paste" user "Package Geometry/Pastemask Top")
		(15 "B.Paste" user "Package Geometry/Pastemask Bottom")
		(5 "F.SilkS" user "Ref Des/Silkscreen Top")
		(7 "B.SilkS" user "Ref Des/Silkscreen Bottom")
		(1 "F.Mask" user "Board Geometry/Soldermask Top")
		(3 "B.Mask" user "Board Geometry/Soldermask Bottom")
		(17 "Dwgs.User" user "User.Drawings")
		(19 "Cmts.User" user "User.Comments")
		(21 "Eco1.User" user "User.Eco1")
		(23 "Eco2.User" user "User.Eco2")
		(25 "Edge.Cuts" user "Board Geometry/Outline")
		(27 "Margin" user)
		(31 "F.CrtYd" user "Package Geometry/Place Bound Top")
		(29 "B.CrtYd" user "Package Geometry/Place Bound Bottom")
		(35 "F.Fab" user "Ref Des/Assembly Top")
		(33 "B.Fab" user "Ref Des/Assembly Bottom")
	)
	(footprint ""
		(layer "F.Cu")
		(at 376.367548 -153.347928)
		(property "Reference" "EU7A3"
			(at 3.320288 -0.2032 90)
			(unlocked yes)
			(layer "F.SilkS")
			(effects
				(font
					(size 0.7874 0.5842)
					(thickness 0.1524)
				)
			)
		)
		(property "Value" ""
			(at 0 0 0)
			(layer "F.Fab")
			(effects
				(font
					(size 1.27 1.27)
				)
			)
		)
		(duplicate_pad_numbers_are_jumpers no)
		(fp_line
			(start -3.0099 -3.5052)
			(end 2.9718 -3.5052)
			(stroke
				(width 0.1524)
				(type default)
			)
			(layer "F.SilkS")
		)
		(fp_line
			(start -3.0099 3.429)
			(end -3.0099 -3.5052)
			(stroke
				(width 0.1524)
				(type default)
			)
			(layer "F.SilkS")
		)
		(fp_line
			(start 2.9718 -3.5052)
			(end 2.9718 3.429)
			(stroke
				(width 0.1524)
				(type default)
			)
			(layer "F.SilkS")
		)
		(fp_line
			(start 2.9718 3.429)
			(end -3.0099 3.429)
			(stroke
				(width 0.1524)
				(type default)
			)
			(layer "F.SilkS")
		)
		(fp_circle
			(center -3.057398 -2.678684)
			(end -2.930398 -2.678684)
			(stroke
				(width 0.254)
				(type default)
			)
			(fill no)
			(layer "F.SilkS")
		)
		(fp_poly
			(pts
				(xy -2.9972 -3.4925) (xy -2.9972 -2.6924) (xy -2.1971 -3.4925)
			)
			(stroke
				(width 0)
				(type default)
			)
			(fill yes)
			(layer "F.SilkS")
		)
		(fp_poly
			(pts
				(xy -2.549906 -3.050032) (xy -2.549906 3.050032) (xy 2.549906 3.050032) (xy 2.549906 -3.050032)
			)
			(stroke
				(width 0)
				(type default)
			)
			(fill no)
			(layer "F.CrtYd")
		)
		(fp_line
			(start -2.549906 -3.050032)
			(end 2.549906 -3.050032)
			(stroke
				(width 0.1)
				(type default)
			)
			(layer "F.Fab")
		)
		(fp_line
			(start -2.549906 3.050032)
			(end -2.549906 -3.050032)
			(stroke
				(width 0.1)
				(type default)
			)
			(layer "F.Fab")
		)
		(fp_line
			(start 2.549906 -3.050032)
			(end 2.549906 3.050032)
			(stroke
				(width 0.1)
				(type default)
			)
			(layer "F.Fab")
		)
		(fp_line
			(start 2.549906 3.050032)
			(end -2.549906 3.050032)
			(stroke
				(width 0.1)
				(type default)
			)
			(layer "F.Fab")
		)
		(fp_circle
			(center -3.057398 -2.678684)
			(end -2.930398 -2.678684)
			(stroke
				(width 0.254)
				(type default)
			)
			(fill no)
			(layer "F.Fab")
		)
		(pad "1" smd rect
			(at -2.39522 -2.279904)
			(size 0.7112 0.254)
			(layers "F.Cu" "F.Mask" "F.Paste")
			(net "PVNN_PCH_STBY")
		)
		(pad "2" smd rect
			(at -2.39522 -1.83007)
			(size 0.7112 0.254)
			(layers "F.Cu" "F.Mask" "F.Paste")
			(net "GND")
		)
		(pad "3" smd rect
			(at -2.39522 -1.379982)
			(size 0.7112 0.254)
			(layers "F.Cu" "F.Mask" "F.Paste")
			(net "VR_PVNN_PCH_PH1_VCIN")
		)
		(pad "4" smd rect
			(at -2.39522 -0.929894)
			(size 0.7112 0.254)
			(layers "F.Cu" "F.Mask" "F.Paste")
			(net "P5V_STBY")
		)
		(pad "5" smd rect
			(at -2.39522 -0.48006)
			(size 0.7112 0.254)
			(layers "F.Cu" "F.Mask" "F.Paste")
			(net "GND")
		)
		(pad "6" smd rect
			(at -2.39522 -0.029972)
			(size 0.7112 0.254)
			(layers "F.Cu" "F.Mask" "F.Paste")
			(net "TP_PVNN_PCH_GL_0")
		)
		(pad "7" smd custom
			(at 0.016764 1.145032)
			(size 0.53975 0.53975)
			(layers "F.Cu" "F.Mask" "F.Paste")
			(net "GND")
			(options
				(clearance outline)
				(anchor circle)
			)
			(primitives
				(gr_poly
					(pts
						(xy -2.7051 1.0795) (xy -2.7051 -0.3683) (xy -0.9271 -0.3683) (xy -0.9271 -1.0795) (xy 2.7051 -1.0795)
						(xy 2.7051 1.0795)
					)
					(width 0)
					(fill yes)
				)
			)
		)
		(pad "10" smd rect
			(at -0.008382 2.874772)
			(size 4.3434 0.6096)
			(layers "F.Cu" "F.Mask" "F.Paste")
			(net "VR_PVNN_PCH_PH1_PHASE_SW")
		)
		(pad "25" smd rect
			(at 1.548384 -1.283208)
			(size 2.3368 2.0066)
			(layers "F.Cu" "F.Mask" "F.Paste")
			(net "VR_FET_SW_P12V_STBY_PVDDQ_DEF")
		)
		(pad "30" smd rect
			(at 2.050034 -2.895092)
			(size 0.254 0.7112)
			(layers "F.Cu" "F.Mask" "F.Paste")
			(net "VR_FET_SW_P12V_STBY_PVDDQ_DEF")
		)
		(pad "31" smd rect
			(at 1.599946 -2.895092)
			(size 0.254 0.7112)
			(layers "F.Cu" "F.Mask" "F.Paste")
			(net "Net_374")
		)
		(pad "32" smd rect
			(at 1.150112 -2.895092)
			(size 0.254 0.7112)
			(layers "F.Cu" "F.Mask" "F.Paste")
			(net "VR_PVNN_PCH_PH1_PHASE")
		)
		(pad "33" smd rect
			(at 0.700024 -2.895092)
			(size 0.254 0.7112)
			(layers "F.Cu" "F.Mask" "F.Paste")
			(net "VR_PVNN_PCH_PH1_BOOT_R")
		)
		(pad "34" smd rect
			(at 0.249936 -2.895092)
			(size 0.254 0.7112)
			(layers "F.Cu" "F.Mask" "F.Paste")
			(net "VR_PVNN_PCH_PWM1")
		)
		(pad "35" smd rect
			(at -0.199898 -2.895092)
			(size 0.254 0.7112)
			(layers "F.Cu" "F.Mask" "F.Paste")
			(net "P5V_STBY")
		)
		(pad "36" smd rect
			(at -0.649986 -2.895092)
			(size 0.254 0.7112)
			(layers "F.Cu" "F.Mask" "F.Paste")
			(net "A_TSENSE_PVNN_PCH_TMON")
		)
		(pad "37" smd rect
			(at -1.100074 -2.895092)
			(size 0.254 0.7112)
			(layers "F.Cu" "F.Mask" "F.Paste")
			(net "VR_PVNN_PCH_STBY_OCSET")
		)
		(pad "38" smd rect
			(at -1.549908 -2.895092)
			(size 0.254 0.7112)
			(layers "F.Cu" "F.Mask" "F.Paste")
			(net "ISENSE_PVNN_PCH_PH1_IMON")
		)
		(pad "39" smd rect
			(at -1.999996 -2.895092)
			(size 0.254 0.7112)
			(layers "F.Cu" "F.Mask" "F.Paste")
			(net "VR_PVNN_PCH_AIREF1")
		)
		(pad "40" smd rect
			(at -0.871728 -1.283208)
			(size 1.8034 2.0066)
			(layers "F.Cu" "F.Mask" "F.Paste")
			(net "GND")
		)
		(pad "41" smd rect
			(at -1.533906 0.247904)
			(size 0.508 0.3556)
			(layers "F.Cu" "F.Mask" "F.Paste")
			(net "TP_PVNN_PCH_GL_1")
		)
	)
)
